(kicad_pcb
	(version 20260206)
	(generator "pcbnew")
	(generator_version "10.0")
	(general
		(thickness 1.6)
		(legacy_teardrops no)
	)
	(paper "A4")
	(title_block
		(title "Bryce Canyon_R.DPB_16317-1_OCP.brd")
		(comment 1 "Bryce Canyon / footprints 448-451 of 2099")
	)
	(layers
		(0 "F.Cu" signal "TOP")
		(4 "In1.Cu" signal "L2GND")
		(6 "In2.Cu" signal "L3")
		(8 "In3.Cu" signal "L4VCC")
		(10 "In4.Cu" signal "L5VCC")
		(12 "In5.Cu" signal "L6")
		(14 "In6.Cu" signal "L7GND")
		(2 "B.Cu" signal "BOTTOM")
		(9 "F.Adhes" user "F.Adhesive")
		(11 "B.Adhes" user "B.Adhesive")
		(13 "F.Paste" user "Package Geometry/Pastemask Top")
		(15 "B.Paste" user "Package Geometry/Pastemask Bottom")
		(5 "F.SilkS" user "Ref Des/Silkscreen Top")
		(7 "B.SilkS" user "Ref Des/Silkscreen Bottom")
		(1 "F.Mask" user "Board Geometry/Soldermask Top")
		(3 "B.Mask" user "Board Geometry/Soldermask Bottom")
		(17 "Dwgs.User" user "User.Drawings")
		(19 "Cmts.User" user "User.Comments")
		(21 "Eco1.User" user "User.Eco1")
		(23 "Eco2.User" user "User.Eco2")
		(25 "Edge.Cuts" user "Board Geometry/Outline")
		(27 "Margin" user)
		(31 "F.CrtYd" user "Package Geometry/Place Bound Top")
		(29 "B.CrtYd" user "Package Geometry/Place Bound Bottom")
		(35 "F.Fab" user "Ref Des/Assembly Top")
		(33 "B.Fab" user "Ref Des/Assembly Bottom")
	)
	(footprint ""
		(layer "F.Cu")
		(at 425.228004 -367.157 -90)
		(property "Reference" "D44"
			(at 0 0 270)
			(layer "F.SilkS")
			(hide yes)
			(effects
				(font
					(size 1.27 1.27)
				)
			)
		)
		(property "Value" "BAS16H-GP"
			(at 0 -5.5372 270)
			(unlocked yes)
			(layer "F.Fab")
			(hide yes)
			(effects
				(font
					(size 1.016 1.016)
					(thickness 0.1524)
				)
			)
		)
		(property "Device Type" "SOD123AKH48"
			(at 0 -7.0612 270)
			(unlocked yes)
			(layer "F.Fab")
			(hide yes)
			(effects
				(font
					(size 1.016 1.016)
					(thickness 0.1524)
				)
			)
		)
		(duplicate_pad_numbers_are_jumpers no)
		(fp_line
			(start 0.889 2.921)
			(end -0.889 2.921)
			(stroke
				(width 0.508)
				(type default)
			)
			(layer "F.SilkS")
		)
		(fp_line
			(start -1.016 2.667)
			(end 1.016 2.667)
			(stroke
				(width 0.1524)
				(type default)
			)
			(layer "F.SilkS")
		)
		(fp_line
			(start 1.016 2.667)
			(end 1.016 -2.667)
			(stroke
				(width 0.1524)
				(type default)
			)
			(layer "F.SilkS")
		)
		(fp_line
			(start -1.016 -2.667)
			(end -1.016 2.667)
			(stroke
				(width 0.1524)
				(type default)
			)
			(layer "F.SilkS")
		)
		(fp_line
			(start 1.016 -2.667)
			(end -1.016 -2.667)
			(stroke
				(width 0.1524)
				(type default)
			)
			(layer "F.SilkS")
		)
		(fp_rect
			(start -1.143 3.175)
			(end 1.143 -2.794)
			(stroke
				(width 0)
				(type default)
			)
			(fill no)
			(layer "F.CrtYd")
		)
		(fp_poly
			(pts
				(xy -1.143 -2.794) (xy 1.143 -2.794) (xy 1.143 3.175) (xy -1.143 3.175)
			)
			(stroke
				(width 0)
				(type default)
			)
			(fill no)
			(layer "F.Fab")
		)
		(pad "A" smd rect
			(at 0 -1.6891 270)
			(size 0.889 1.397)
			(layers "F.Cu" "F.Mask" "F.Paste")
			(net "FAN_3_TACH1")
		)
		(pad "K" smd rect
			(at 0 1.6891 270)
			(size 0.889 1.397)
			(layers "F.Cu" "F.Mask" "F.Paste")
			(net "P12V_IN")
		)
	)
	(footprint ""
		(layer "F.Cu")
		(at 382.88595 -13.6271 180)
		(property "Reference" "VIA65"
			(at 0 0 180)
			(layer "F.SilkS")
			(hide yes)
			(effects
				(font
					(size 1.27 1.27)
				)
			)
		)
		(property "Value" "100OHM-8L-2D36MM-L18-GP"
			(at 3.8989 0.5715 180)
			(unlocked yes)
			(layer "F.Fab")
			(hide yes)
			(effects
				(font
					(size 1.016 1.016)
					(thickness 0.1524)
				)
			)
		)
		(property "Device Type" "VIA-PCIE-4P-414097"
			(at 3.8989 -0.9525 180)
			(unlocked yes)
			(layer "F.Fab")
			(hide yes)
			(effects
				(font
					(size 1.016 1.016)
					(thickness 0.1524)
				)
			)
		)
		(duplicate_pad_numbers_are_jumpers no)
		(fp_rect
			(start -2.0701 0.4826)
			(end 2.0701 -0.4826)
			(stroke
				(width 0)
				(type default)
			)
			(fill no)
			(layer "F.CrtYd")
		)
		(fp_rect
			(start -2.0701 0.4826)
			(end 2.0701 -0.4826)
			(stroke
				(width 0)
				(type default)
			)
			(fill no)
			(layer "F.Fab")
		)
		(pad "1" thru_hole circle
			(at -1.5875 0 180)
			(size 0.508 0.508)
			(drill 0.254)
			(layers "*.Cu" "*.Mask")
			(remove_unused_layers no)
			(net "GND")
			(clearance 0.2286)
			(thermal_gap 0.2286)
		)
		(pad "2" thru_hole circle
			(at -0.5715 0 180)
			(size 0.508 0.508)
			(drill 0.254)
			(layers "*.Cu" "*.Mask")
			(remove_unused_layers no)
			(net "PHY_SCC_B_TO_DRV_B_32_DP")
			(clearance 0.2286)
			(thermal_gap 0.2286)
		)
		(pad "3" thru_hole circle
			(at 0.5715 0 180)
			(size 0.508 0.508)
			(drill 0.254)
			(layers "*.Cu" "*.Mask")
			(remove_unused_layers no)
			(net "PHY_SCC_B_TO_DRV_B_32_DN")
			(clearance 0.2286)
			(thermal_gap 0.2286)
		)
		(pad "4" thru_hole circle
			(at 1.5875 0 180)
			(size 0.508 0.508)
			(drill 0.254)
			(layers "*.Cu" "*.Mask")
			(remove_unused_layers no)
			(net "GND")
			(clearance 0.2286)
			(thermal_gap 0.2286)
		)
	)
	(footprint ""
		(layer "F.Cu")
		(at 307.089048 -356.060756 90)
		(property "Reference" "R503"
			(at 0 0 90)
			(layer "F.SilkS")
			(hide yes)
			(effects
				(font
					(size 1.27 1.27)
				)
			)
		)
		(property "Value" "10KR2F-2-GP"
			(at 0.064008 -3.993896 90)
			(unlocked yes)
			(layer "F.Fab")
			(hide yes)
			(effects
				(font
					(size 1.016 1.016)
					(thickness 0.1524)
				)
			)
		)
		(property "Device Type" "R402H16"
			(at 0.064008 -5.517896 90)
			(unlocked yes)
			(layer "F.Fab")
			(hide yes)
			(effects
				(font
					(size 1.016 1.016)
					(thickness 0.1524)
				)
			)
		)
		(duplicate_pad_numbers_are_jumpers no)
		(fp_line
			(start 0.508 -0.9398)
			(end -0.508 -0.9398)
			(stroke
				(width 0.1524)
				(type default)
			)
			(layer "F.SilkS")
		)
		(fp_line
			(start -0.508 -0.9398)
			(end -0.508 0.9398)
			(stroke
				(width 0.1524)
				(type default)
			)
			(layer "F.SilkS")
		)
		(fp_rect
			(start -0.508 0.9398)
			(end 0.508 -0.9398)
			(stroke
				(width 0)
				(type default)
			)
			(fill no)
			(layer "F.CrtYd")
		)
		(fp_rect
			(start -0.508 0.9398)
			(end 0.508 -0.9398)
			(stroke
				(width 0)
				(type default)
			)
			(fill no)
			(layer "F.Fab")
		)
		(pad "1" smd custom
			(at 0 -0.4445 90)
			(size 0.1397 0.1397)
			(layers "F.Cu" "F.Mask" "F.Paste")
			(net "P3V3_IN")
			(options
				(clearance outline)
				(anchor circle)
			)
			(primitives
				(gr_poly
					(pts
						(arc
							(start -0.1778 -0.2794)
							(mid -0.249642 -0.249642)
							(end -0.2794 -0.1778)
						)
						(arc
							(start -0.2794 0.1778)
							(mid -0.249642 0.249642)
							(end -0.1778 0.2794)
						)
						(arc
							(start 0.1778 0.2794)
							(mid 0.249642 0.249642)
							(end 0.2794 0.1778)
						)
						(arc
							(start 0.2794 -0.1778)
							(mid 0.249642 -0.249642)
							(end 0.1778 -0.2794)
						)
					)
					(width 0)
					(fill yes)
				)
			)
		)
		(pad "2" smd custom
			(at 0 0.4445 90)
			(size 0.1397 0.1397)
			(layers "F.Cu" "F.Mask" "F.Paste")
			(net "FANTACH_B_OE_N")
			(options
				(clearance outline)
				(anchor circle)
			)
			(primitives
				(gr_poly
					(pts
						(arc
							(start -0.1778 -0.2794)
							(mid -0.249642 -0.249642)
							(end -0.2794 -0.1778)
						)
						(arc
							(start -0.2794 0.1778)
							(mid -0.249642 0.249642)
							(end -0.1778 0.2794)
						)
						(arc
							(start 0.1778 0.2794)
							(mid 0.249642 0.249642)
							(end 0.2794 0.1778)
						)
						(arc
							(start 0.2794 -0.1778)
							(mid 0.249642 -0.249642)
							(end 0.1778 -0.2794)
						)
					)
					(width 0)
					(fill yes)
				)
			)
		)
	)
	(footprint ""
		(layer "F.Cu")
		(at 420.200074 -143.91005 -90)
		(property "Reference" "HDDSAS21"
			(at 0 0 270)
			(layer "F.SilkS")
			(hide yes)
			(effects
				(font
					(size 1.27 1.27)
				)
			)
		)
		(property "Value" "SKT-SAS15P-14P-45-GP"
			(at -20.7645 -8.9789 270)
			(unlocked yes)
			(layer "F.Fab")
			(hide yes)
			(effects
				(font
					(size 1.016 1.016)
					(thickness 0.1524)
				)
			)
		)
		(property "Device Type" "10120818-001C-TRLF"
			(at -20.7645 -10.5029 270)
			(unlocked yes)
			(layer "F.Fab")
			(hide yes)
			(effects
				(font
					(size 1.016 1.016)
					(thickness 0.1524)
				)
			)
		)
		(duplicate_pad_numbers_are_jumpers no)
		(fp_line
			(start 1.651 4.2926)
			(end 1.651 3.0099)
			(stroke
				(width 0.1524)
				(type default)
			)
			(layer "F.SilkS")
		)
		(fp_line
			(start 8.509 4.2926)
			(end 1.651 4.2926)
			(stroke
				(width 0.1524)
				(type default)
			)
			(layer "F.SilkS")
		)
		(fp_line
			(start -23.4188 3.0099)
			(end -23.4188 -3.2512)
			(stroke
				(width 0.1524)
				(type default)
			)
			(layer "F.SilkS")
		)
		(fp_line
			(start 1.651 3.0099)
			(end -23.4188 3.0099)
			(stroke
				(width 0.1524)
				(type default)
			)
			(layer "F.SilkS")
		)
		(fp_line
			(start 8.509 3.0099)
			(end 8.509 4.2926)
			(stroke
				(width 0.1524)
				(type default)
			)
			(layer "F.SilkS")
		)
		(fp_line
			(start 23.4188 3.0099)
			(end 8.509 3.0099)
			(stroke
				(width 0.1524)
				(type default)
			)
			(layer "F.SilkS")
		)
		(fp_line
			(start -23.4188 -3.2512)
			(end 23.4188 -3.2512)
			(stroke
				(width 0.1524)
				(type default)
			)
			(layer "F.SilkS")
		)
		(fp_line
			(start 23.4188 -3.2512)
			(end 23.4188 3.0099)
			(stroke
				(width 0.1524)
				(type default)
			)
			(layer "F.SilkS")
		)
		(fp_line
			(start 15.5067 -3.3401)
			(end 16.2687 -3.3401)
			(stroke
				(width 0.3302)
				(type default)
			)
			(layer "F.SilkS")
		)
		(fp_poly
			(pts
				(xy 15.868904 -3.230372) (xy 16.503904 -3.865372) (xy 15.233904 -3.865372)
			)
			(stroke
				(width 0)
				(type default)
			)
			(fill yes)
			(layer "F.SilkS")
		)
		(fp_poly
			(pts
				(xy -22.8727 -2.7559) (xy 22.8727 -2.7559) (xy 22.8727 2.7559) (xy 8.255 2.7559) (xy 8.255 3.5179)
				(xy 1.905 3.5179) (xy 1.905 2.7559) (xy -22.8727 2.7559)
			)
			(stroke
				(width 0)
				(type default)
			)
			(fill no)
			(layer "F.CrtYd")
		)
		(fp_poly
			(pts
				(xy 1.397 4.5466) (xy 1.397 3.2639) (xy -23.6728 3.2639) (xy -23.6728 -3.5052) (xy 23.6728 -3.5052)
				(xy 23.6728 -0.00635) (xy 22.8727 -0.00635) (xy 22.8727 -2.7559) (xy -22.8727 -2.7559) (xy -22.8727 2.7559)
				(xy 1.905 2.7559) (xy 1.905 3.5179) (xy 8.255 3.5179) (xy 8.255 2.7559) (xy 22.8727 2.7559) (xy 22.8727 0.00635)
				(xy 23.6728 0.00635) (xy 23.6728 3.2639) (xy 8.763 3.2639) (xy 8.763 4.5466)
			)
			(stroke
				(width 0)
				(type default)
			)
			(fill no)
			(layer "F.CrtYd")
		)
		(fp_poly
			(pts
				(xy 1.397 4.5466) (xy 1.397 3.2639) (xy -23.6728 3.2639) (xy -23.6728 -3.5052) (xy 23.6728 -3.5052)
				(xy 23.6728 3.2639) (xy 8.763 3.2639) (xy 8.763 4.5466)
			)
			(stroke
				(width 0)
				(type default)
			)
			(fill no)
			(layer "F.Fab")
		)
		(pad "" np_thru_hole circle
			(at -18.874994 0 270)
			(size 0.254 0.254)
			(drill 1.3462)
			(layers "*.Cu" "*.Mask")
			(clearance 0.9017)
			(thermal_gap 0.9017)
		)
		(pad "" np_thru_hole circle
			(at 18.874994 0 270)
			(size 0.254 0.254)
			(drill 0.9398)
			(layers "*.Cu" "*.Mask")
			(clearance 0.6985)
			(thermal_gap 0.6985)
		)
		(pad "G1" smd rect
			(at 21.874988 0 270)
			(size 2.5908 2.5908)
			(layers "F.Cu" "F.Mask" "F.Paste")
			(net "GND")
		)
		(pad "G2" smd rect
			(at -21.874988 0 270)
			(size 2.5908 2.5908)
			(layers "F.Cu" "F.Mask" "F.Paste")
			(net "GND")
		)
		(pad "P1" smd rect
			(at 1.905 -1.82499 270)
			(size 0.6096 2.3622)
			(layers "F.Cu" "F.Mask" "F.Paste")
			(net "Net_1694")
		)
		(pad "P2" smd rect
			(at 0.635 -1.82499 270)
			(size 0.6096 2.3622)
			(layers "F.Cu" "F.Mask" "F.Paste")
			(net "Net_1695")
		)
		(pad "P3" smd rect
			(at -0.635 -1.82499 270)
			(size 0.6096 2.3622)
			(layers "F.Cu" "F.Mask" "F.Paste")
			(net "Net_1696")
		)
		(pad "P4" smd rect
			(at -1.905 -1.82499 270)
			(size 0.6096 2.3622)
			(layers "F.Cu" "F.Mask" "F.Paste")
			(net "GND")
		)
		(pad "P5" smd rect
			(at -3.175 -1.82499 270)
			(size 0.6096 2.3622)
			(layers "F.Cu" "F.Mask" "F.Paste")
			(net "HDD_PRSNT_21")
		)
		(pad "P6" smd rect
			(at -4.445 -1.82499 270)
			(size 0.6096 2.3622)
			(layers "F.Cu" "F.Mask" "F.Paste")
			(net "GND")
		)
		(pad "P7" smd rect
			(at -5.715 -1.82499 270)
			(size 0.6096 2.3622)
			(layers "F.Cu" "F.Mask" "F.Paste")
			(net "5V_PRE_21")
		)
		(pad "P8" smd rect
			(at -6.985 -1.82499 270)
			(size 0.6096 2.3622)
			(layers "F.Cu" "F.Mask" "F.Paste")
			(net "P5V_HDD21")
		)
		(pad "P9" smd rect
			(at -8.255 -1.82499 270)
			(size 0.6096 2.3622)
			(layers "F.Cu" "F.Mask" "F.Paste")
			(net "P5V_HDD21")
		)
		(pad "P10" smd rect
			(at -9.525 -1.82499 270)
			(size 0.6096 2.3622)
			(layers "F.Cu" "F.Mask" "F.Paste")
			(net "GND")
		)
		(pad "P11" smd rect
			(at -10.795 -1.82499 270)
			(size 0.6096 2.3622)
			(layers "F.Cu" "F.Mask" "F.Paste")
			(net "ACT_HDD_21")
		)
		(pad "P12" smd rect
			(at -12.065 -1.82499 270)
			(size 0.6096 2.3622)
			(layers "F.Cu" "F.Mask" "F.Paste")
			(net "GND")
		)
		(pad "P13" smd rect
			(at -13.335 -1.82499 270)
			(size 0.6096 2.3622)
			(layers "F.Cu" "F.Mask" "F.Paste")
			(net "12V_PRE_21")
		)
		(pad "P14" smd rect
			(at -14.605 -1.82499 270)
			(size 0.6096 2.3622)
			(layers "F.Cu" "F.Mask" "F.Paste")
			(net "P12V_HDD21")
		)
		(pad "P15" smd rect
			(at -15.875 -1.82499 270)
			(size 0.6096 2.3622)
			(layers "F.Cu" "F.Mask" "F.Paste")
			(net "P12V_HDD21")
		)
		(pad "S1" smd rect
			(at 15.875 -1.82499 270)
			(size 0.6096 2.3622)
			(layers "F.Cu" "F.Mask" "F.Paste")
			(net "GND")
		)
		(pad "S2" smd rect
			(at 14.605 -1.82499 270)
			(size 0.6096 2.3622)
			(layers "F.Cu" "F.Mask" "F.Paste")
			(net "SAS_HDD_RX_P21")
		)
		(pad "S3" smd rect
			(at 13.335 -1.82499 270)
			(size 0.6096 2.3622)
			(layers "F.Cu" "F.Mask" "F.Paste")
			(net "SAS_HDD_RX_N21")
		)
		(pad "S4" smd rect
			(at 12.065 -1.82499 270)
			(size 0.6096 2.3622)
			(layers "F.Cu" "F.Mask" "F.Paste")
			(net "GND")
		)
		(pad "S5" smd rect
			(at 10.795 -1.82499 270)
			(size 0.6096 2.3622)
			(layers "F.Cu" "F.Mask" "F.Paste")
			(net "PHY_DRV_B_TO_SCC_B_21_DN")
		)
		(pad "S6" smd rect
			(at 9.525 -1.82499 270)
			(size 0.6096 2.3622)
			(layers "F.Cu" "F.Mask" "F.Paste")
			(net "PHY_DRV_B_TO_SCC_B_21_DP")
		)
		(pad "S7" smd rect
			(at 8.255 -1.82499 270)
			(size 0.6096 2.3622)
			(layers "F.Cu" "F.Mask" "F.Paste")
			(net "GND")
		)
		(pad "S8" smd rect
			(at 7.480046 2.845054 270)
			(size 0.508 2.3622)
			(layers "F.Cu" "F.Mask" "F.Paste")
			(net "GND")
		)
		(pad "S9" smd rect
			(at 6.679946 2.845054 270)
			(size 0.508 2.3622)
			(layers "F.Cu" "F.Mask" "F.Paste")
			(net "Net_445")
		)
		(pad "S10" smd rect
			(at 5.8801 2.845054 270)
			(size 0.508 2.3622)
			(layers "F.Cu" "F.Mask" "F.Paste")
			(net "Net_337")
		)
		(pad "S11" smd rect
			(at 5.08 2.845054 270)
			(size 0.508 2.3622)
			(layers "F.Cu" "F.Mask" "F.Paste")
			(net "GND")
		)
		(pad "S12" smd rect
			(at 4.2799 2.845054 270)
			(size 0.508 2.3622)
			(layers "F.Cu" "F.Mask" "F.Paste")
			(net "Net_373")
		)
		(pad "S13" smd rect
			(at 3.480054 2.845054 270)
			(size 0.508 2.3622)
			(layers "F.Cu" "F.Mask" "F.Paste")
			(net "Net_409")
		)
		(pad "S14" smd rect
			(at 2.679954 2.845054 270)
			(size 0.508 2.3622)
			(layers "F.Cu" "F.Mask" "F.Paste")
			(net "GND")
		)
		(zone
			(layer "F.Cu")
			(hatch none 0.5)
			(connect_pads
				(clearance 0)
			)
			(min_thickness 0.25)
			(keepout
				(tracks allowed)
				(vias not_allowed)
				(pads allowed)
				(copperpour not_allowed)
				(footprints allowed)
			)
			(placement
				(enabled no)
				(sheetname "")
			)
			(fill
				(thermal_gap 0.5)
				(thermal_bridge_width 0.5)
				(island_removal_mode 0)
			)
			(polygon
				(pts
					(xy 423.857674 -160.64865) (xy 416.783774 -160.64865) (xy 416.783774 -167.58285) (xy 417.888674 -167.58285)
					(xy 417.888674 -163.46805) (xy 422.511474 -163.46805) (xy 422.511474 -167.58285) (xy 423.857674 -167.58285)
				)
			)
		)
		(zone
			(layer "F.Cu")
			(hatch none 0.5)
			(connect_pads
				(clearance 0)
			)
			(min_thickness 0.25)
			(keepout
				(tracks not_allowed)
				(vias allowed)
				(pads allowed)
				(copperpour not_allowed)
				(footprints allowed)
			)
			(placement
				(enabled no)
				(sheetname "")
			)
			(fill
				(thermal_gap 0.5)
				(thermal_bridge_width 0.5)
				(island_removal_mode 0)
			)
			(polygon
				(pts
					(xy 423.857674 -160.64865) (xy 416.783774 -160.64865) (xy 416.783774 -167.58285) (xy 417.888674 -167.58285)
					(xy 417.888674 -163.46805) (xy 422.511474 -163.46805) (xy 422.511474 -167.58285) (xy 423.857674 -167.58285)
				)
			)
		)
		(zone
			(layer "F.Cu")
			(hatch none 0.5)
			(connect_pads
				(clearance 0)
			)
			(min_thickness 0.25)
			(keepout
				(tracks not_allowed)
				(vias allowed)
				(pads allowed)
				(copperpour not_allowed)
				(footprints allowed)
			)
			(placement
				(enabled no)
				(sheetname "")
			)
			(fill
				(thermal_gap 0.5)
				(thermal_bridge_width 0.5)
				(island_removal_mode 0)
			)
			(polygon
				(pts
					(xy 423.857674 -127.17145) (xy 416.783774 -127.17145) (xy 416.783774 -120.23725) (xy 417.888674 -120.23725)
					(xy 417.888674 -124.35205) (xy 422.511474 -124.35205) (xy 422.511474 -120.23725) (xy 423.857674 -120.23725)
				)
			)
		)
		(zone
			(layer "F.Cu")
			(hatch none 0.5)
			(connect_pads
				(clearance 0)
			)
			(min_thickness 0.25)
			(keepout
				(tracks allowed)
				(vias not_allowed)
				(pads allowed)
				(copperpour not_allowed)
				(footprints allowed)
			)
			(placement
				(enabled no)
				(sheetname "")
			)
			(fill
				(thermal_gap 0.5)
				(thermal_bridge_width 0.5)
				(island_removal_mode 0)
			)
			(polygon
				(pts
					(xy 423.857674 -127.17145) (xy 416.783774 -127.17145) (xy 416.783774 -120.23725) (xy 417.888674 -120.23725)
					(xy 417.888674 -124.35205) (xy 422.511474 -124.35205) (xy 422.511474 -120.23725) (xy 423.857674 -120.23725)
				)
			)
		)
		(zone
			(layers "F.Cu" "B.Cu" "In1.Cu" "In2.Cu" "In3.Cu" "In4.Cu" "In5.Cu" "In6.Cu")
			(hatch none 0.5)
			(connect_pads
				(clearance 0)
			)
			(min_thickness 0.25)
			(keepout
				(tracks not_allowed)
				(vias allowed)
				(pads allowed)
				(copperpour not_allowed)
				(footprints allowed)
			)
			(placement
				(enabled no)
				(sheetname "")
			)
			(fill
				(thermal_gap 0.5)
				(thermal_bridge_width 0.5)
				(island_removal_mode 0)
			)
			(polygon
				(pts
					(arc
						(start 420.974774 -125.035056)
						(mid 419.425374 -125.035056)
						(end 420.974774 -125.035056)
					)
				)
			)
		)
		(zone
			(layers "F.Cu" "B.Cu" "In1.Cu" "In2.Cu" "In3.Cu" "In4.Cu" "In5.Cu" "In6.Cu")
			(hatch none 0.5)
			(connect_pads
				(clearance 0)
			)
			(min_thickness 0.25)
			(keepout
				(tracks not_allowed)
				(vias allowed)
				(pads allowed)
				(copperpour not_allowed)
				(footprints allowed)
			)
			(placement
				(enabled no)
				(sheetname "")
			)
			(fill
				(thermal_gap 0.5)
				(thermal_bridge_width 0.5)
				(island_removal_mode 0)
			)
			(polygon
				(pts
					(arc
						(start 421.177974 -162.785044)
						(mid 419.222174 -162.785044)
						(end 421.177974 -162.785044)
					)
				)
			)
		)
	)
)
